(kicad_pcb
	(version 20260206)
	(generator "pcbnew")
	(generator_version "10.0")
	(general
		(thickness 1.6)
		(legacy_teardrops no)
	)
	(paper "A4")
	(title_block
		(title "timecard-production-celestica-r4006 — R4006-B0001-02_R01.brd")
		(comment 1 "Time Appliance Project (Time Card) / footprints 443-447 of 1113")
	)
	(layers
		(0 "F.Cu" signal "TOP")
		(4 "In1.Cu" signal "L02_GND1")
		(6 "In2.Cu" signal "L03_SIG1")
		(8 "In3.Cu" signal "L04_GND2")
		(10 "In4.Cu" signal "L05_VCC1")
		(12 "In5.Cu" signal "L06_VCC2")
		(14 "In6.Cu" signal "L07_GND3")
		(16 "In7.Cu" signal "L08_SIG2")
		(18 "In8.Cu" signal "L09_GND4")
		(2 "B.Cu" signal "BOTTOM")
		(9 "F.Adhes" user "F.Adhesive")
		(11 "B.Adhes" user "B.Adhesive")
		(13 "F.Paste" user "Package Geometry/Pastemask Top")
		(15 "B.Paste" user "Package Geometry/Pastemask Bottom")
		(5 "F.SilkS" user "Ref Des/Silkscreen Top")
		(7 "B.SilkS" user "Ref Des/Silkscreen Bottom")
		(1 "F.Mask" user "Board Geometry/Soldermask Top")
		(3 "B.Mask" user "Board Geometry/Soldermask Bottom")
		(17 "Dwgs.User" user "User.Drawings")
		(19 "Cmts.User" user "User.Comments")
		(21 "Eco1.User" user "User.Eco1")
		(23 "Eco2.User" user "User.Eco2")
		(25 "Edge.Cuts" user "Board Geometry/Outline")
		(27 "Margin" user)
		(31 "F.CrtYd" user "Package Geometry/Place Bound Top")
		(29 "B.CrtYd" user "Package Geometry/Place Bound Bottom")
		(35 "F.Fab" user "Ref Des/Assembly Top")
		(33 "B.Fab" user "Ref Des/Assembly Bottom")
	)
	(footprint ""
		(layer "F.Cu")
		(at 112.649 -90.805)
		(property "Reference" "Q1"
			(at 2.667 -0.08763 0)
			(unlocked yes)
			(layer "F.SilkS")
			(effects
				(font
					(size 0.7874 0.5842)
					(thickness 0.1524)
				)
			)
		)
		(property "Value" ""
			(at 0 0 0)
			(layer "F.Fab")
			(effects
				(font
					(size 1.27 1.27)
				)
			)
		)
		(property "User Part Number" "PARTNUM*"
			(at -0.074676 4.841748 0)
			(unlocked yes)
			(layer "Cmts.User")
			(hide yes)
			(effects
				(font
					(size 0.7874 0.5842)
					(thickness 0.000001)
				)
			)
		)
		(property "Device Type" "POWERMOS_3P_NCH_V1-G121-10200-A"
			(at -0.051562 3.91414 0)
			(unlocked yes)
			(layer "F.Fab")
			(hide yes)
			(effects
				(font
					(size 0.7874 0.5842)
					(thickness 0.000001)
				)
			)
		)
		(duplicate_pad_numbers_are_jumpers no)
		(fp_line
			(start -1.7018 -0.9144)
			(end -0.7493 -0.9144)
			(stroke
				(width 0.1)
				(type default)
			)
			(layer "F.SilkS")
		)
		(fp_line
			(start -1.7018 2.0574)
			(end -1.7018 -0.9144)
			(stroke
				(width 0.1)
				(type default)
			)
			(layer "F.SilkS")
		)
		(fp_line
			(start -0.7493 -2.0574)
			(end 0.7493 -2.0574)
			(stroke
				(width 0.1)
				(type default)
			)
			(layer "F.SilkS")
		)
		(fp_line
			(start -0.7493 -0.9144)
			(end -0.7493 -2.0574)
			(stroke
				(width 0.1)
				(type default)
			)
			(layer "F.SilkS")
		)
		(fp_line
			(start -0.1905 0.9144)
			(end -0.1905 2.0574)
			(stroke
				(width 0.1)
				(type default)
			)
			(layer "F.SilkS")
		)
		(fp_line
			(start -0.1905 2.0574)
			(end -1.7018 2.0574)
			(stroke
				(width 0.1)
				(type default)
			)
			(layer "F.SilkS")
		)
		(fp_line
			(start 0.1905 0.9144)
			(end -0.1905 0.9144)
			(stroke
				(width 0.1)
				(type default)
			)
			(layer "F.SilkS")
		)
		(fp_line
			(start 0.1905 2.0574)
			(end 0.1905 0.9144)
			(stroke
				(width 0.1)
				(type default)
			)
			(layer "F.SilkS")
		)
		(fp_line
			(start 0.7493 -2.0574)
			(end 0.7493 -0.9144)
			(stroke
				(width 0.1)
				(type default)
			)
			(layer "F.SilkS")
		)
		(fp_line
			(start 0.7493 -0.9144)
			(end 1.7018 -0.9144)
			(stroke
				(width 0.1)
				(type default)
			)
			(layer "F.SilkS")
		)
		(fp_line
			(start 1.7018 -0.9144)
			(end 1.7018 2.0574)
			(stroke
				(width 0.1)
				(type default)
			)
			(layer "F.SilkS")
		)
		(fp_line
			(start 1.7018 2.0574)
			(end 0.1905 2.0574)
			(stroke
				(width 0.1)
				(type default)
			)
			(layer "F.SilkS")
		)
		(fp_poly
			(pts
				(arc
					(start -0.752856 2.634234)
					(mid -1.514856 2.634234)
					(end -0.752856 2.634234)
				)
			)
			(stroke
				(width 0)
				(type default)
			)
			(fill yes)
			(layer "F.SilkS")
		)
		(fp_poly
			(pts
				(xy -1.7018 2.0828) (xy -1.7018 -0.9144) (xy -0.762 -0.9144) (xy -0.762 -2.0574) (xy 0.762 -2.0574)
				(xy 0.762 -0.9144) (xy 1.7018 -0.9144) (xy 1.7018 2.0828)
			)
			(stroke
				(width 0)
				(type default)
			)
			(fill no)
			(layer "F.CrtYd")
		)
		(fp_line
			(start -1.4478 -0.6604)
			(end -1.3716 -0.5842)
			(stroke
				(width 0.1)
				(type default)
			)
			(layer "F.Fab")
		)
		(fp_line
			(start -1.4478 -0.6604)
			(end 1.4478 -0.6604)
			(stroke
				(width 0.1)
				(type default)
			)
			(layer "F.Fab")
		)
		(fp_line
			(start -1.4478 0.6604)
			(end -1.4478 -0.6604)
			(stroke
				(width 0.1)
				(type default)
			)
			(layer "F.Fab")
		)
		(fp_line
			(start -1.4478 0.6604)
			(end -1.3716 0.5842)
			(stroke
				(width 0.1)
				(type default)
			)
			(layer "F.Fab")
		)
		(fp_line
			(start -1.3716 -0.5842)
			(end 1.3716 -0.5842)
			(stroke
				(width 0.1)
				(type default)
			)
			(layer "F.Fab")
		)
		(fp_line
			(start -1.3716 0.5842)
			(end -1.3716 -0.5842)
			(stroke
				(width 0.1)
				(type default)
			)
			(layer "F.Fab")
		)
		(fp_line
			(start -1.1684 0.6604)
			(end -0.7112 0.6604)
			(stroke
				(width 0.1)
				(type default)
			)
			(layer "F.Fab")
		)
		(fp_line
			(start -1.1684 0.9144)
			(end -0.7112 0.9144)
			(stroke
				(width 0.1)
				(type default)
			)
			(layer "F.Fab")
		)
		(fp_line
			(start -1.1684 1.143)
			(end -1.1684 0.6604)
			(stroke
				(width 0.1)
				(type default)
			)
			(layer "F.Fab")
		)
		(fp_line
			(start -0.7112 0.6604)
			(end -0.7112 1.143)
			(stroke
				(width 0.1)
				(type default)
			)
			(layer "F.Fab")
		)
		(fp_line
			(start -0.7112 1.143)
			(end -1.1684 1.143)
			(stroke
				(width 0.1)
				(type default)
			)
			(layer "F.Fab")
		)
		(fp_line
			(start -0.2286 -1.143)
			(end 0.2286 -1.143)
			(stroke
				(width 0.1)
				(type default)
			)
			(layer "F.Fab")
		)
		(fp_line
			(start -0.2286 -0.9144)
			(end 0.2286 -0.9144)
			(stroke
				(width 0.1)
				(type default)
			)
			(layer "F.Fab")
		)
		(fp_line
			(start -0.2286 -0.6604)
			(end -0.2286 -1.143)
			(stroke
				(width 0.1)
				(type default)
			)
			(layer "F.Fab")
		)
		(fp_line
			(start 0.2286 -1.143)
			(end 0.2286 -0.6604)
			(stroke
				(width 0.1)
				(type default)
			)
			(layer "F.Fab")
		)
		(fp_line
			(start 0.2286 -0.6604)
			(end -0.2286 -0.6604)
			(stroke
				(width 0.1)
				(type default)
			)
			(layer "F.Fab")
		)
		(fp_line
			(start 0.7112 0.6604)
			(end 1.1684 0.6604)
			(stroke
				(width 0.1)
				(type default)
			)
			(layer "F.Fab")
		)
		(fp_line
			(start 0.7112 0.9144)
			(end 1.1684 0.9144)
			(stroke
				(width 0.1)
				(type default)
			)
			(layer "F.Fab")
		)
		(fp_line
			(start 0.7112 1.143)
			(end 0.7112 0.6604)
			(stroke
				(width 0.1)
				(type default)
			)
			(layer "F.Fab")
		)
		(fp_line
			(start 1.1684 0.6604)
			(end 1.1684 1.143)
			(stroke
				(width 0.1)
				(type default)
			)
			(layer "F.Fab")
		)
		(fp_line
			(start 1.1684 1.143)
			(end 0.7112 1.143)
			(stroke
				(width 0.1)
				(type default)
			)
			(layer "F.Fab")
		)
		(fp_line
			(start 1.3716 -0.5842)
			(end 1.3716 0.5842)
			(stroke
				(width 0.1)
				(type default)
			)
			(layer "F.Fab")
		)
		(fp_line
			(start 1.3716 -0.5842)
			(end 1.4478 -0.6604)
			(stroke
				(width 0.1)
				(type default)
			)
			(layer "F.Fab")
		)
		(fp_line
			(start 1.3716 0.5842)
			(end -1.3716 0.5842)
			(stroke
				(width 0.1)
				(type default)
			)
			(layer "F.Fab")
		)
		(fp_line
			(start 1.3716 0.5842)
			(end 1.4478 0.6604)
			(stroke
				(width 0.1)
				(type default)
			)
			(layer "F.Fab")
		)
		(fp_line
			(start 1.4478 -0.6604)
			(end 1.4478 0.6604)
			(stroke
				(width 0.1)
				(type default)
			)
			(layer "F.Fab")
		)
		(fp_line
			(start 1.4478 0.6604)
			(end -1.4478 0.6604)
			(stroke
				(width 0.1)
				(type default)
			)
			(layer "F.Fab")
		)
		(fp_poly
			(pts
				(arc
					(start -0.752856 2.634234)
					(mid -1.514856 2.634234)
					(end -0.752856 2.634234)
				)
			)
			(stroke
				(width 0)
				(type default)
			)
			(fill yes)
			(layer "F.Fab")
		)
		(fp_text user "2"
			(at 1.651 2.70637 0)
			(unlocked yes)
			(layer "F.SilkS")
			(effects
				(font
					(size 0.7874 0.5842)
					(thickness 0.1524)
				)
			)
		)
		(fp_text user "2"
			(at 0.931418 2.683764 0)
			(unlocked yes)
			(layer "F.Fab")
			(effects
				(font
					(size 0.7874 0.5842)
					(thickness 0.1524)
				)
			)
		)
		(pad "1" smd rect
			(at -0.9398 1.1049)
			(size 0.9906 1.397)
			(layers "F.Cu" "F.Mask" "F.Paste")
			(net "FT_USB_DETECT")
		)
		(pad "2" smd rect
			(at 0.9398 1.1049)
			(size 0.9906 1.397)
			(layers "F.Cu" "F.Mask" "F.Paste")
			(net "SG")
		)
		(pad "3" smd rect
			(at 0 -1.1049)
			(size 0.9906 1.397)
			(layers "F.Cu" "F.Mask" "F.Paste")
			(net "UNNAMED_524_POWERMOS3PNCHV1_I44")
		)
	)
	(footprint ""
		(layer "F.Cu")
		(at 93.4974 -78.7146)
		(property "Reference" "L11"
			(at -4.0259 -0.24003 0)
			(unlocked yes)
			(layer "F.SilkS")
			(effects
				(font
					(size 0.7874 0.5842)
					(thickness 0.1524)
				)
				(justify left)
			)
		)
		(property "Value" "VAL*"
			(at -0.9398 3.70967 0)
			(unlocked yes)
			(layer "F.Fab")
			(hide yes)
			(effects
				(font
					(size 0.7874 0.5842)
					(thickness 0.1524)
				)
				(justify left)
			)
		)
		(property "Tolerance" "TOL*"
			(at -0.9906 5.00507 0)
			(unlocked yes)
			(layer "Cmts.User")
			(hide yes)
			(effects
				(font
					(size 0.7874 0.5842)
					(thickness 0.1524)
				)
				(justify left)
			)
		)
		(property "User Part Number" "PARTNUM*"
			(at -2.54 2.46507 0)
			(unlocked yes)
			(layer "Cmts.User")
			(hide yes)
			(effects
				(font
					(size 0.7874 0.5842)
					(thickness 0.1524)
				)
				(justify left)
			)
		)
		(property "Device Type" "FERRITEBEAD-G191-10101-01,26OHA"
			(at -0.9906 1.22047 0)
			(unlocked yes)
			(layer "F.Fab")
			(hide yes)
			(effects
				(font
					(size 0.7874 0.5842)
					(thickness 0.1524)
				)
				(justify left)
			)
		)
		(duplicate_pad_numbers_are_jumpers no)
		(fp_line
			(start -1.3208 -0.7112)
			(end 1.3208 -0.7112)
			(stroke
				(width 0.1)
				(type default)
			)
			(layer "F.SilkS")
		)
		(fp_line
			(start -1.3208 0.7112)
			(end -1.3208 -0.7112)
			(stroke
				(width 0.1)
				(type default)
			)
			(layer "F.SilkS")
		)
		(fp_line
			(start 1.3208 -0.7112)
			(end 1.3208 0.7112)
			(stroke
				(width 0.1)
				(type default)
			)
			(layer "F.SilkS")
		)
		(fp_line
			(start 1.3208 0.7112)
			(end -1.3208 0.7112)
			(stroke
				(width 0.1)
				(type default)
			)
			(layer "F.SilkS")
		)
		(fp_rect
			(start -1.3208 -0.7112)
			(end 1.3208 0.7112)
			(stroke
				(width 0)
				(type default)
			)
			(fill no)
			(layer "F.CrtYd")
		)
		(fp_line
			(start -0.8128 -0.4572)
			(end 0.8128 -0.4572)
			(stroke
				(width 0.1)
				(type default)
			)
			(layer "F.Fab")
		)
		(fp_line
			(start -0.8128 0.4572)
			(end -0.8128 -0.4572)
			(stroke
				(width 0.1)
				(type default)
			)
			(layer "F.Fab")
		)
		(fp_line
			(start 0.8128 -0.4572)
			(end 0.8128 0.4572)
			(stroke
				(width 0.1)
				(type default)
			)
			(layer "F.Fab")
		)
		(fp_line
			(start 0.8128 0.4572)
			(end -0.8128 0.4572)
			(stroke
				(width 0.1)
				(type default)
			)
			(layer "F.Fab")
		)
		(pad "1" smd rect
			(at -0.6858 0)
			(size 0.762 0.8636)
			(layers "F.Cu" "F.Mask" "F.Paste")
			(net "XP3R3V")
		)
		(pad "2" smd rect
			(at 0.6858 0)
			(size 0.762 0.8636)
			(layers "F.Cu" "F.Mask" "F.Paste")
			(net "XP1R2V_VIN")
		)
		(zone
			(layer "F.Cu")
			(hatch none 0.5)
			(connect_pads
				(clearance 0)
			)
			(min_thickness 0.25)
			(keepout
				(tracks allowed)
				(vias not_allowed)
				(pads allowed)
				(copperpour not_allowed)
				(footprints allowed)
			)
			(placement
				(enabled no)
				(sheetname "")
			)
			(fill
				(thermal_gap 0.5)
				(thermal_bridge_width 0.5)
				(island_removal_mode 0)
			)
			(polygon
				(pts
					(xy 93.345 -79.1718) (xy 93.345 -78.2574) (xy 93.6498 -78.2574) (xy 93.6498 -79.1718)
				)
			)
		)
	)
	(footprint ""
		(layer "F.Cu")
		(at 51.2318 -83.2866 -90)
		(property "Reference" "TP23"
			(at -0.8382 0.01143 90)
			(unlocked yes)
			(layer "F.SilkS")
			(effects
				(font
					(size 0.7874 0.5842)
					(thickness 0.1524)
				)
				(justify left)
			)
		)
		(property "Value" ""
			(at 0 0 270)
			(layer "F.Fab")
			(effects
				(font
					(size 1.27 1.27)
				)
			)
		)
		(property "Device Type" "TP_PIONT-TP010CT020B030_PTH-TPA"
			(at -1.341882 0.996696 270)
			(unlocked yes)
			(layer "F.Fab")
			(hide yes)
			(effects
				(font
					(size 0.7874 0.5842)
					(thickness 0.000001)
				)
				(justify left)
			)
		)
		(duplicate_pad_numbers_are_jumpers no)
		(fp_poly
			(pts
				(arc
					(start 0 -0.889)
					(mid 0 0.889)
					(end 0 -0.889)
				)
			)
			(stroke
				(width 0)
				(type default)
			)
			(fill no)
			(layer "B.CrtYd")
		)
		(fp_poly
			(pts
				(arc
					(start 0 -0.889)
					(mid 0 0.889)
					(end 0 -0.889)
				)
			)
			(stroke
				(width 0)
				(type default)
			)
			(fill no)
			(layer "F.CrtYd")
		)
		(pad "1" thru_hole circle
			(at 0 0 270)
			(size 0.508 0.508)
			(drill 0.254)
			(layers "*.Cu" "*.Mask")
			(remove_unused_layers no)
			(net "FPGA_IN_LM75B_INT2_N")
			(clearance 0.1016)
			(padstack
				(mode front_inner_back)
				(layer "Inner"
					(shape circle)
					(size 0.508 0.508)
					(clearance 0.1016)
				)
				(layer "B.Cu"
					(shape circle)
					(size 0.762 0.762)
					(clearance -0.0254)
				)
			)
		)
	)
	(footprint ""
		(layer "F.Cu")
		(at 14.605 -57.531)
		(property "Reference" "TP28"
			(at 0.66675 2.8194 90)
			(unlocked yes)
			(layer "F.SilkS")
			(effects
				(font
					(size 0.635 0.4064)
					(thickness 0.1524)
				)
				(justify left)
			)
		)
		(property "Value" ""
			(at 0 0 0)
			(layer "F.Fab")
			(effects
				(font
					(size 1.27 1.27)
				)
			)
		)
		(property "Device Type" "TP_PIONT-TP010CT020B030_PTH-TPA"
			(at -1.341882 0.996696 0)
			(unlocked yes)
			(layer "F.Fab")
			(hide yes)
			(effects
				(font
					(size 0.7874 0.5842)
					(thickness 0.000001)
				)
				(justify left)
			)
		)
		(duplicate_pad_numbers_are_jumpers no)
		(fp_poly
			(pts
				(arc
					(start 0.889 0)
					(mid -0.889 0)
					(end 0.889 0)
				)
			)
			(stroke
				(width 0)
				(type default)
			)
			(fill no)
			(layer "B.CrtYd")
		)
		(fp_poly
			(pts
				(arc
					(start 0.889 0)
					(mid -0.889 0)
					(end 0.889 0)
				)
			)
			(stroke
				(width 0)
				(type default)
			)
			(fill no)
			(layer "F.CrtYd")
		)
		(pad "1" thru_hole circle
			(at 0 0)
			(size 0.508 0.508)
			(drill 0.254)
			(layers "*.Cu" "*.Mask")
			(remove_unused_layers no)
			(net "SMA1_SIG_IN_BF_EN_N")
			(clearance 0.1016)
			(padstack
				(mode front_inner_back)
				(layer "Inner"
					(shape circle)
					(size 0.508 0.508)
					(clearance 0.1016)
				)
				(layer "B.Cu"
					(shape circle)
					(size 0.762 0.762)
					(clearance -0.0254)
				)
			)
		)
	)
	(footprint ""
		(layer "F.Cu")
		(at 150.749 -26.035)
		(property "Reference" "R21"
			(at -0.381 2.83337 0)
			(unlocked yes)
			(layer "F.SilkS")
			(effects
				(font
					(size 0.7874 0.5842)
					(thickness 0.1524)
				)
			)
		)
		(property "Value" "VAL*"
			(at 0.02032 2.13233 0)
			(unlocked yes)
			(layer "F.Fab")
			(hide yes)
			(effects
				(font
					(size 0.7874 0.5842)
					(thickness 0.1524)
				)
			)
		)
		(property "Tolerance" "TOL*"
			(at 0.044704 3.05435 0)
			(unlocked yes)
			(layer "Cmts.User")
			(hide yes)
			(effects
				(font
					(size 0.7874 0.5842)
					(thickness 0.1524)
				)
			)
		)
		(property "User Part Number" "PARTNUM*"
			(at 0.02032 4.024884 0)
			(unlocked yes)
			(layer "Cmts.User")
			(hide yes)
			(effects
				(font
					(size 0.7874 0.5842)
					(thickness 0.1524)
				)
			)
		)
		(property "Device Type" "RESISTOR-G155-14701-01,4.7KOHMA"
			(at 0.008382 1.210564 0)
			(unlocked yes)
			(layer "F.Fab")
			(hide yes)
			(effects
				(font
					(size 0.7874 0.5842)
					(thickness 0.1524)
				)
			)
		)
		(duplicate_pad_numbers_are_jumpers no)
		(fp_line
			(start -1.143 -0.5588)
			(end -1.143 0.5588)
			(stroke
				(width 0.1)
				(type default)
			)
			(layer "F.SilkS")
		)
		(fp_line
			(start -1.143 0.5588)
			(end 1.143 0.5588)
			(stroke
				(width 0.1)
				(type default)
			)
			(layer "F.SilkS")
		)
		(fp_line
			(start 1.143 -0.5588)
			(end -1.143 -0.5588)
			(stroke
				(width 0.1)
				(type default)
			)
			(layer "F.SilkS")
		)
		(fp_line
			(start 1.143 0.5588)
			(end 1.143 -0.5588)
			(stroke
				(width 0.1)
				(type default)
			)
			(layer "F.SilkS")
		)
		(fp_rect
			(start -1.143 -0.5588)
			(end 1.143 0.5588)
			(stroke
				(width 0)
				(type default)
			)
			(fill no)
			(layer "F.CrtYd")
		)
		(fp_line
			(start -0.508 -0.3048)
			(end -0.508 0.3048)
			(stroke
				(width 0.1)
				(type default)
			)
			(layer "F.Fab")
		)
		(fp_line
			(start -0.508 0.3048)
			(end 0.508 0.3048)
			(stroke
				(width 0.1)
				(type default)
			)
			(layer "F.Fab")
		)
		(fp_line
			(start 0.508 -0.3048)
			(end -0.508 -0.3048)
			(stroke
				(width 0.1)
				(type default)
			)
			(layer "F.Fab")
		)
		(fp_line
			(start 0.508 0.3048)
			(end 0.508 -0.3048)
			(stroke
				(width 0.1)
				(type default)
			)
			(layer "F.Fab")
		)
		(pad "1" smd rect
			(at -0.5334 0)
			(size 0.7112 0.6096)
			(layers "F.Cu" "F.Mask" "F.Paste")
			(net "XP3R3V_FPGA")
		)
		(pad "2" smd rect
			(at 0.5334 0)
			(size 0.7112 0.6096)
			(layers "F.Cu" "F.Mask" "F.Paste")
			(net "LM75B_I2C_SCL")
		)
		(zone
			(layer "F.Cu")
			(hatch none 0.5)
			(connect_pads
				(clearance 0)
			)
			(min_thickness 0.25)
			(keepout
				(tracks allowed)
				(vias not_allowed)
				(pads allowed)
				(copperpour not_allowed)
				(footprints allowed)
			)
			(placement
				(enabled no)
				(sheetname "")
			)
			(fill
				(thermal_gap 0.5)
				(thermal_bridge_width 0.5)
				(island_removal_mode 0)
			)
			(polygon
				(pts
					(xy 150.6728 -26.3398) (xy 150.6728 -25.7302) (xy 150.8252 -25.7302) (xy 150.8252 -26.3398)
				)
			)
		)
	)
)
